(kicad_pcb
	(version 20260206)
	(generator "pcbnew")
	(generator_version "10.0")
	(general
		(thickness 1.6)
		(legacy_teardrops no)
	)
	(paper "A4")
	(title_block
		(title "01162023_DA0F0TEBIF0_F0T_Expander_BD_F_brd_V02_OCP.brd")
		(comment 1 "Grand Teton / footprints 4491-4497 of 9728")
	)
	(layers
		(0 "F.Cu" signal "TOP")
		(4 "In1.Cu" signal "GND")
		(6 "In2.Cu" signal "VCC")
		(8 "In3.Cu" signal "VCC1")
		(10 "In4.Cu" signal "GND1")
		(12 "In5.Cu" signal "IN1")
		(14 "In6.Cu" signal "GND2")
		(16 "In7.Cu" signal "IN2")
		(18 "In8.Cu" signal "GND3")
		(20 "In9.Cu" signal "IN3")
		(22 "In10.Cu" signal "GND4")
		(24 "In11.Cu" signal "IN4")
		(26 "In12.Cu" signal "GND5")
		(28 "In13.Cu" signal "IN5")
		(30 "In14.Cu" signal "GND6")
		(32 "In15.Cu" signal "IN6")
		(34 "In16.Cu" signal "GND7")
		(2 "B.Cu" signal "BOTTOM")
		(9 "F.Adhes" user "F.Adhesive")
		(11 "B.Adhes" user "B.Adhesive")
		(13 "F.Paste" user "Package Geometry/Pastemask Top")
		(15 "B.Paste" user "Package Geometry/Pastemask Bottom")
		(5 "F.SilkS" user "Ref Des/Silkscreen Top")
		(7 "B.SilkS" user "Ref Des/Silkscreen Bottom")
		(1 "F.Mask" user "Board Geometry/Soldermask Top")
		(3 "B.Mask" user "Board Geometry/Soldermask Bottom")
		(17 "Dwgs.User" user "User.Drawings")
		(19 "Cmts.User" user "User.Comments")
		(21 "Eco1.User" user "User.Eco1")
		(23 "Eco2.User" user "User.Eco2")
		(25 "Edge.Cuts" user "Board Geometry/Outline")
		(27 "Margin" user)
		(31 "F.CrtYd" user "Package Geometry/Place Bound Top")
		(29 "B.CrtYd" user "Package Geometry/Place Bound Bottom")
		(35 "F.Fab" user "Ref Des/Assembly Top")
		(33 "B.Fab" user "Ref Des/Assembly Bottom")
	)
	(footprint ""
		(layer "F.Cu")
		(at 320.354452 -225.929698 180)
		(property "Reference" "D13"
			(at 3.743452 0.103632 0)
			(unlocked yes)
			(layer "F.SilkS")
			(effects
				(font
					(size 0.7874 0.5842)
					(thickness 0.1524)
				)
				(justify left)
			)
		)
		(property "Value" ""
			(at 0 0 180)
			(layer "F.Fab")
			(effects
				(font
					(size 1.27 1.27)
				)
			)
		)
		(duplicate_pad_numbers_are_jumpers no)
		(fp_line
			(start 1.16078 0.4826)
			(end -0.64008 0.4826)
			(stroke
				(width 0.1524)
				(type default)
			)
			(layer "F.SilkS")
		)
		(fp_line
			(start 1.16078 -0.4826)
			(end 1.16078 0.4826)
			(stroke
				(width 0.1524)
				(type default)
			)
			(layer "F.SilkS")
		)
		(fp_line
			(start 1.03378 0.4826)
			(end -0.79248 0.4826)
			(stroke
				(width 0.1524)
				(type default)
			)
			(layer "F.SilkS")
		)
		(fp_line
			(start 1.03378 -0.4826)
			(end 1.03378 0.4826)
			(stroke
				(width 0.1524)
				(type default)
			)
			(layer "F.SilkS")
		)
		(fp_line
			(start 0.90678 0.4826)
			(end -0.90678 0.4826)
			(stroke
				(width 0.1524)
				(type default)
			)
			(layer "F.SilkS")
		)
		(fp_line
			(start 0.90678 -0.4826)
			(end 0.90678 0.4826)
			(stroke
				(width 0.1524)
				(type default)
			)
			(layer "F.SilkS")
		)
		(fp_line
			(start -0.64008 -0.4826)
			(end 1.16078 -0.4826)
			(stroke
				(width 0.1524)
				(type default)
			)
			(layer "F.SilkS")
		)
		(fp_line
			(start -0.79248 -0.4826)
			(end 1.03378 -0.4826)
			(stroke
				(width 0.1524)
				(type default)
			)
			(layer "F.SilkS")
		)
		(fp_line
			(start -0.89408 -0.4826)
			(end 0.90678 -0.4826)
			(stroke
				(width 0.1524)
				(type default)
			)
			(layer "F.SilkS")
		)
		(fp_line
			(start -0.90678 0.4826)
			(end -0.90678 -0.4699)
			(stroke
				(width 0.1524)
				(type default)
			)
			(layer "F.SilkS")
		)
		(fp_line
			(start 0.499872 0.249936)
			(end -0.499872 0.249936)
			(stroke
				(width 0.1)
				(type default)
			)
			(layer "F.Fab")
		)
		(fp_line
			(start 0.499872 -0.249936)
			(end 0.499872 0.249936)
			(stroke
				(width 0.1)
				(type default)
			)
			(layer "F.Fab")
		)
		(fp_line
			(start -0.499872 0.249936)
			(end -0.499872 -0.249936)
			(stroke
				(width 0.1)
				(type default)
			)
			(layer "F.Fab")
		)
		(fp_line
			(start -0.499872 -0.249936)
			(end 0.499872 -0.249936)
			(stroke
				(width 0.1)
				(type default)
			)
			(layer "F.Fab")
		)
		(pad "A" smd rect
			(at -0.47498 0 180)
			(size 0.6096 0.7112)
			(layers "F.Cu" "F.Mask" "F.Paste")
			(net "LED_POSTCODE_R_0")
		)
		(pad "C" smd rect
			(at 0.47498 0 180)
			(size 0.6096 0.7112)
			(layers "F.Cu" "F.Mask" "F.Paste")
			(net "FPGA_DEBUG_LED_R_N")
		)
	)
	(footprint ""
		(layer "F.Cu")
		(at 168.71061 -18.61439 90)
		(property "Reference" "U131"
			(at -1.34239 2.33426 90)
			(unlocked yes)
			(layer "F.SilkS")
			(effects
				(font
					(size 0.7874 0.5842)
					(thickness 0.1524)
				)
				(justify left)
			)
		)
		(property "Value" ""
			(at 0 0 90)
			(layer "F.Fab")
			(effects
				(font
					(size 1.27 1.27)
				)
			)
		)
		(duplicate_pad_numbers_are_jumpers no)
		(fp_line
			(start 1.463548 -1.549908)
			(end 1.463548 1.549908)
			(stroke
				(width 0.1524)
				(type default)
			)
			(layer "F.SilkS")
		)
		(fp_line
			(start 0.762 -1.549908)
			(end 1.463548 -1.549908)
			(stroke
				(width 0.1524)
				(type default)
			)
			(layer "F.SilkS")
		)
		(fp_line
			(start -0.787908 -1.549908)
			(end 0 -0.762)
			(stroke
				(width 0.1524)
				(type default)
			)
			(layer "F.SilkS")
		)
		(fp_line
			(start -1.463548 -1.549908)
			(end -0.787908 -1.549908)
			(stroke
				(width 0.1524)
				(type default)
			)
			(layer "F.SilkS")
		)
		(fp_line
			(start 0 -0.762)
			(end 0.762 -1.549908)
			(stroke
				(width 0.1524)
				(type default)
			)
			(layer "F.SilkS")
		)
		(fp_line
			(start 1.463548 1.549908)
			(end -1.463548 1.549908)
			(stroke
				(width 0.1524)
				(type default)
			)
			(layer "F.SilkS")
		)
		(fp_line
			(start -1.463548 1.549908)
			(end -1.463548 -1.549908)
			(stroke
				(width 0.1524)
				(type default)
			)
			(layer "F.SilkS")
		)
		(fp_poly
			(pts
				(xy -3.4798 -1.359916) (xy -2.86004 -1.050036) (xy -3.4798 -0.740156)
			)
			(stroke
				(width 0)
				(type default)
			)
			(fill yes)
			(layer "F.SilkS")
		)
		(fp_line
			(start 1.549908 -1.549908)
			(end 1.549908 1.549908)
			(stroke
				(width 0.1)
				(type default)
			)
			(layer "F.Fab")
		)
		(fp_line
			(start -1.549908 -1.549908)
			(end 1.549908 -1.549908)
			(stroke
				(width 0.1)
				(type default)
			)
			(layer "F.Fab")
		)
		(fp_line
			(start 1.549908 1.549908)
			(end -1.549908 1.549908)
			(stroke
				(width 0.1)
				(type default)
			)
			(layer "F.Fab")
		)
		(fp_line
			(start -1.549908 1.549908)
			(end -1.549908 -1.549908)
			(stroke
				(width 0.1)
				(type default)
			)
			(layer "F.Fab")
		)
		(fp_poly
			(pts
				(xy -3.4798 -1.359916) (xy -2.86004 -1.050036) (xy -3.4798 -0.740156)
			)
			(stroke
				(width 0)
				(type default)
			)
			(fill yes)
			(layer "F.Fab")
		)
		(pad "1" smd rect
			(at -2.175002 -1.050036 180)
			(size 0.6096 1.1684)
			(layers "F.Cu" "F.Mask" "F.Paste")
			(net "P3V3_SSD5")
		)
		(pad "2" smd rect
			(at -2.175002 -0.32512 180)
			(size 0.4318 1.1684)
			(layers "F.Cu" "F.Mask" "F.Paste")
			(net "SMB_ISO_SSD5_SCL")
		)
		(pad "3" smd rect
			(at -2.175002 0.32512 180)
			(size 0.4318 1.1684)
			(layers "F.Cu" "F.Mask" "F.Paste")
			(net "SMB_ISO_SSD5_SDA")
		)
		(pad "4" smd rect
			(at -2.175002 1.050036 180)
			(size 0.6096 1.1684)
			(layers "F.Cu" "F.Mask" "F.Paste")
			(net "GND")
		)
		(pad "5" smd rect
			(at 2.175002 1.050036 180)
			(size 0.6096 1.1684)
			(layers "F.Cu" "F.Mask" "F.Paste")
			(net "SMB_SSD5_ISO_EN")
		)
		(pad "6" smd rect
			(at 2.175002 0.32512 180)
			(size 0.4318 1.1684)
			(layers "F.Cu" "F.Mask" "F.Paste")
			(net "SMB_BIC_I2C9_MUX0_SSD5_R_SDA")
		)
		(pad "7" smd rect
			(at 2.175002 -0.32512 180)
			(size 0.4318 1.1684)
			(layers "F.Cu" "F.Mask" "F.Paste")
			(net "SMB_BIC_I2C9_MUX0_SSD5_R_SCL")
		)
		(pad "8" smd rect
			(at 2.175002 -1.050036 180)
			(size 0.6096 1.1684)
			(layers "F.Cu" "F.Mask" "F.Paste")
			(net "P3V3_AUX")
		)
	)
	(footprint ""
		(layer "F.Cu")
		(at 407.615136 -20.72513)
		(property "Reference" "H105"
			(at 1.502664 -2.613914 0)
			(unlocked yes)
			(layer "B.SilkS")
			(effects
				(font
					(size 0.7874 0.5842)
					(thickness 0.1524)
				)
				(justify left mirror)
			)
		)
		(property "Value" ""
			(at 0 0 0)
			(layer "F.Fab")
			(effects
				(font
					(size 1.27 1.27)
				)
			)
		)
		(duplicate_pad_numbers_are_jumpers no)
		(pad "1" thru_hole rect
			(at 0 0)
			(size 4.2164 5.0038)
			(drill 2.0066
				(offset 0.099822 0)
			)
			(layers "*.Cu" "*.Mask")
			(remove_unused_layers no)
			(net "Net_8558")
			(clearance -0.8509)
			(padstack
				(mode front_inner_back)
				(layer "Inner"
					(shape circle)
					(size 4.0132 4.0132)
					(clearance -0.7493)
				)
				(layer "B.Cu"
					(shape circle)
					(size 4.0132 4.0132)
					(clearance -0.7493)
				)
			)
		)
	)
	(footprint ""
		(layer "F.Cu")
		(at 176.279048 -59.577986 -90)
		(property "Reference" "R891"
			(at 0 0 270)
			(layer "F.SilkS")
			(hide yes)
			(effects
				(font
					(size 1.27 1.27)
				)
			)
		)
		(property "Value" ""
			(at 0 0 270)
			(layer "F.Fab")
			(effects
				(font
					(size 1.27 1.27)
				)
			)
		)
		(duplicate_pad_numbers_are_jumpers no)
		(fp_line
			(start -0.7874 0.4064)
			(end -0.7874 -0.4064)
			(stroke
				(width 0.1524)
				(type default)
			)
			(layer "F.SilkS")
		)
		(fp_line
			(start 0.7874 0.4064)
			(end -0.7874 0.4064)
			(stroke
				(width 0.1524)
				(type default)
			)
			(layer "F.SilkS")
		)
		(fp_line
			(start -0.7874 -0.4064)
			(end 0.7874 -0.4064)
			(stroke
				(width 0.1524)
				(type default)
			)
			(layer "F.SilkS")
		)
		(fp_line
			(start 0.7874 -0.4064)
			(end 0.7874 0.4064)
			(stroke
				(width 0.1524)
				(type default)
			)
			(layer "F.SilkS")
		)
		(fp_line
			(start -0.67945 0.3048)
			(end -0.67945 -0.305054)
			(stroke
				(width 0.1)
				(type default)
			)
			(layer "F.Fab")
		)
		(fp_line
			(start -0.12065 0.3048)
			(end -0.67945 0.3048)
			(stroke
				(width 0.1)
				(type default)
			)
			(layer "F.Fab")
		)
		(fp_line
			(start 0.120396 0.3048)
			(end 0.120396 0.2794)
			(stroke
				(width 0.1)
				(type default)
			)
			(layer "F.Fab")
		)
		(fp_line
			(start 0.67945 0.3048)
			(end 0.120396 0.3048)
			(stroke
				(width 0.1)
				(type default)
			)
			(layer "F.Fab")
		)
		(fp_line
			(start -0.12065 0.2794)
			(end -0.12065 0.3048)
			(stroke
				(width 0.1)
				(type default)
			)
			(layer "F.Fab")
		)
		(fp_line
			(start 0.120396 0.2794)
			(end -0.12065 0.2794)
			(stroke
				(width 0.1)
				(type default)
			)
			(layer "F.Fab")
		)
		(fp_line
			(start -0.12065 -0.2794)
			(end 0.12065 -0.2794)
			(stroke
				(width 0.1)
				(type default)
			)
			(layer "F.Fab")
		)
		(fp_line
			(start 0.12065 -0.2794)
			(end 0.12065 -0.3048)
			(stroke
				(width 0.1)
				(type default)
			)
			(layer "F.Fab")
		)
		(fp_line
			(start 0.12065 -0.3048)
			(end 0.67945 -0.3048)
			(stroke
				(width 0.1)
				(type default)
			)
			(layer "F.Fab")
		)
		(fp_line
			(start 0.67945 -0.3048)
			(end 0.67945 0.3048)
			(stroke
				(width 0.1)
				(type default)
			)
			(layer "F.Fab")
		)
		(fp_line
			(start -0.67945 -0.305054)
			(end -0.12065 -0.305054)
			(stroke
				(width 0.1)
				(type default)
			)
			(layer "F.Fab")
		)
		(fp_line
			(start -0.12065 -0.305054)
			(end -0.12065 -0.2794)
			(stroke
				(width 0.1)
				(type default)
			)
			(layer "F.Fab")
		)
		(pad "1" smd circle
			(at -0.40005 0 270)
			(size 0 0)
			(layers "F.Cu" "F.Mask" "F.Paste")
			(net "P3V3_SSD6")
		)
		(pad "2" smd circle
			(at 0.40005 0 270)
			(size 0 0)
			(layers "F.Cu" "F.Mask" "F.Paste")
			(net "PWRGD_P3V3_SSD6")
		)
	)
	(footprint ""
		(layer "F.Cu")
		(at 408.42057 -26.666444 -90)
		(property "Reference" "R4081"
			(at 0 0 270)
			(layer "F.SilkS")
			(hide yes)
			(effects
				(font
					(size 1.27 1.27)
				)
			)
		)
		(property "Value" ""
			(at 0 0 270)
			(layer "F.Fab")
			(effects
				(font
					(size 1.27 1.27)
				)
			)
		)
		(duplicate_pad_numbers_are_jumpers no)
		(fp_line
			(start -0.7874 0.4064)
			(end -0.7874 -0.4064)
			(stroke
				(width 0.1524)
				(type default)
			)
			(layer "F.SilkS")
		)
		(fp_line
			(start 0.7874 0.4064)
			(end -0.7874 0.4064)
			(stroke
				(width 0.1524)
				(type default)
			)
			(layer "F.SilkS")
		)
		(fp_line
			(start -0.7874 -0.4064)
			(end 0.7874 -0.4064)
			(stroke
				(width 0.1524)
				(type default)
			)
			(layer "F.SilkS")
		)
		(fp_line
			(start 0.7874 -0.4064)
			(end 0.7874 0.4064)
			(stroke
				(width 0.1524)
				(type default)
			)
			(layer "F.SilkS")
		)
		(fp_line
			(start -0.67945 0.3048)
			(end -0.67945 -0.305054)
			(stroke
				(width 0.1)
				(type default)
			)
			(layer "F.Fab")
		)
		(fp_line
			(start -0.12065 0.3048)
			(end -0.67945 0.3048)
			(stroke
				(width 0.1)
				(type default)
			)
			(layer "F.Fab")
		)
		(fp_line
			(start 0.120396 0.3048)
			(end 0.120396 0.2794)
			(stroke
				(width 0.1)
				(type default)
			)
			(layer "F.Fab")
		)
		(fp_line
			(start 0.67945 0.3048)
			(end 0.120396 0.3048)
			(stroke
				(width 0.1)
				(type default)
			)
			(layer "F.Fab")
		)
		(fp_line
			(start -0.12065 0.2794)
			(end -0.12065 0.3048)
			(stroke
				(width 0.1)
				(type default)
			)
			(layer "F.Fab")
		)
		(fp_line
			(start 0.120396 0.2794)
			(end -0.12065 0.2794)
			(stroke
				(width 0.1)
				(type default)
			)
			(layer "F.Fab")
		)
		(fp_line
			(start -0.12065 -0.2794)
			(end 0.12065 -0.2794)
			(stroke
				(width 0.1)
				(type default)
			)
			(layer "F.Fab")
		)
		(fp_line
			(start 0.12065 -0.2794)
			(end 0.12065 -0.3048)
			(stroke
				(width 0.1)
				(type default)
			)
			(layer "F.Fab")
		)
		(fp_line
			(start 0.12065 -0.3048)
			(end 0.67945 -0.3048)
			(stroke
				(width 0.1)
				(type default)
			)
			(layer "F.Fab")
		)
		(fp_line
			(start 0.67945 -0.3048)
			(end 0.67945 0.3048)
			(stroke
				(width 0.1)
				(type default)
			)
			(layer "F.Fab")
		)
		(fp_line
			(start -0.67945 -0.305054)
			(end -0.12065 -0.305054)
			(stroke
				(width 0.1)
				(type default)
			)
			(layer "F.Fab")
		)
		(fp_line
			(start -0.12065 -0.305054)
			(end -0.12065 -0.2794)
			(stroke
				(width 0.1)
				(type default)
			)
			(layer "F.Fab")
		)
		(pad "1" smd circle
			(at -0.40005 0 270)
			(size 0 0)
			(layers "F.Cu" "F.Mask" "F.Paste")
			(net "PRSNT_SSD14_R_N")
		)
		(pad "2" smd circle
			(at 0.40005 0 270)
			(size 0 0)
			(layers "F.Cu" "F.Mask" "F.Paste")
			(net "PRSNT_SSD14_N")
		)
	)
	(footprint ""
		(layer "F.Cu")
		(at 86.991444 -96.811592 -90)
		(property "Reference" "R692"
			(at 0 0 270)
			(layer "F.SilkS")
			(hide yes)
			(effects
				(font
					(size 1.27 1.27)
				)
			)
		)
		(property "Value" ""
			(at 0 0 270)
			(layer "F.Fab")
			(effects
				(font
					(size 1.27 1.27)
				)
			)
		)
		(duplicate_pad_numbers_are_jumpers no)
		(fp_line
			(start -0.7874 0.4064)
			(end -0.7874 -0.4064)
			(stroke
				(width 0.1524)
				(type default)
			)
			(layer "F.SilkS")
		)
		(fp_line
			(start 0.7874 0.4064)
			(end -0.7874 0.4064)
			(stroke
				(width 0.1524)
				(type default)
			)
			(layer "F.SilkS")
		)
		(fp_line
			(start -0.7874 -0.4064)
			(end 0.7874 -0.4064)
			(stroke
				(width 0.1524)
				(type default)
			)
			(layer "F.SilkS")
		)
		(fp_line
			(start 0.7874 -0.4064)
			(end 0.7874 0.4064)
			(stroke
				(width 0.1524)
				(type default)
			)
			(layer "F.SilkS")
		)
		(fp_line
			(start -0.67945 0.3048)
			(end -0.67945 -0.305054)
			(stroke
				(width 0.1)
				(type default)
			)
			(layer "F.Fab")
		)
		(fp_line
			(start -0.12065 0.3048)
			(end -0.67945 0.3048)
			(stroke
				(width 0.1)
				(type default)
			)
			(layer "F.Fab")
		)
		(fp_line
			(start 0.120396 0.3048)
			(end 0.120396 0.2794)
			(stroke
				(width 0.1)
				(type default)
			)
			(layer "F.Fab")
		)
		(fp_line
			(start 0.67945 0.3048)
			(end 0.120396 0.3048)
			(stroke
				(width 0.1)
				(type default)
			)
			(layer "F.Fab")
		)
		(fp_line
			(start -0.12065 0.2794)
			(end -0.12065 0.3048)
			(stroke
				(width 0.1)
				(type default)
			)
			(layer "F.Fab")
		)
		(fp_line
			(start 0.120396 0.2794)
			(end -0.12065 0.2794)
			(stroke
				(width 0.1)
				(type default)
			)
			(layer "F.Fab")
		)
		(fp_line
			(start -0.12065 -0.2794)
			(end 0.12065 -0.2794)
			(stroke
				(width 0.1)
				(type default)
			)
			(layer "F.Fab")
		)
		(fp_line
			(start 0.12065 -0.2794)
			(end 0.12065 -0.3048)
			(stroke
				(width 0.1)
				(type default)
			)
			(layer "F.Fab")
		)
		(fp_line
			(start 0.12065 -0.3048)
			(end 0.67945 -0.3048)
			(stroke
				(width 0.1)
				(type default)
			)
			(layer "F.Fab")
		)
		(fp_line
			(start 0.67945 -0.3048)
			(end 0.67945 0.3048)
			(stroke
				(width 0.1)
				(type default)
			)
			(layer "F.Fab")
		)
		(fp_line
			(start -0.67945 -0.305054)
			(end -0.12065 -0.305054)
			(stroke
				(width 0.1)
				(type default)
			)
			(layer "F.Fab")
		)
		(fp_line
			(start -0.12065 -0.305054)
			(end -0.12065 -0.2794)
			(stroke
				(width 0.1)
				(type default)
			)
			(layer "F.Fab")
		)
		(pad "1" smd circle
			(at -0.40005 0 270)
			(size 0 0)
			(layers "F.Cu" "F.Mask" "F.Paste")
			(net "NIC1_ADC_A1")
		)
		(pad "2" smd circle
			(at 0.40005 0 270)
			(size 0 0)
			(layers "F.Cu" "F.Mask" "F.Paste")
			(net "P3V3_AUX")
		)
	)
	(footprint ""
		(layer "F.Cu")
		(at 168.545002 -175.182276)
		(property "Reference" "R153"
			(at 0 0 0)
			(layer "F.SilkS")
			(hide yes)
			(effects
				(font
					(size 1.27 1.27)
				)
			)
		)
		(property "Value" ""
			(at 0 0 0)
			(layer "F.Fab")
			(effects
				(font
					(size 1.27 1.27)
				)
			)
		)
		(duplicate_pad_numbers_are_jumpers no)
		(fp_line
			(start -0.7874 -0.4064)
			(end 0.7874 -0.4064)
			(stroke
				(width 0.1524)
				(type default)
			)
			(layer "F.SilkS")
		)
		(fp_line
			(start -0.7874 0.4064)
			(end -0.7874 -0.4064)
			(stroke
				(width 0.1524)
				(type default)
			)
			(layer "F.SilkS")
		)
		(fp_line
			(start 0.7874 -0.4064)
			(end 0.7874 0.4064)
			(stroke
				(width 0.1524)
				(type default)
			)
			(layer "F.SilkS")
		)
		(fp_line
			(start 0.7874 0.4064)
			(end -0.7874 0.4064)
			(stroke
				(width 0.1524)
				(type default)
			)
			(layer "F.SilkS")
		)
		(fp_line
			(start -0.67945 -0.305054)
			(end -0.12065 -0.305054)
			(stroke
				(width 0.1)
				(type default)
			)
			(layer "F.Fab")
		)
		(fp_line
			(start -0.67945 0.3048)
			(end -0.67945 -0.305054)
			(stroke
				(width 0.1)
				(type default)
			)
			(layer "F.Fab")
		)
		(fp_line
			(start -0.12065 -0.305054)
			(end -0.12065 -0.2794)
			(stroke
				(width 0.1)
				(type default)
			)
			(layer "F.Fab")
		)
		(fp_line
			(start -0.12065 -0.2794)
			(end 0.12065 -0.2794)
			(stroke
				(width 0.1)
				(type default)
			)
			(layer "F.Fab")
		)
		(fp_line
			(start -0.12065 0.2794)
			(end -0.12065 0.3048)
			(stroke
				(width 0.1)
				(type default)
			)
			(layer "F.Fab")
		)
		(fp_line
			(start -0.12065 0.3048)
			(end -0.67945 0.3048)
			(stroke
				(width 0.1)
				(type default)
			)
			(layer "F.Fab")
		)
		(fp_line
			(start 0.120396 0.2794)
			(end -0.12065 0.2794)
			(stroke
				(width 0.1)
				(type default)
			)
			(layer "F.Fab")
		)
		(fp_line
			(start 0.120396 0.3048)
			(end 0.120396 0.2794)
			(stroke
				(width 0.1)
				(type default)
			)
			(layer "F.Fab")
		)
		(fp_line
			(start 0.12065 -0.3048)
			(end 0.67945 -0.3048)
			(stroke
				(width 0.1)
				(type default)
			)
			(layer "F.Fab")
		)
		(fp_line
			(start 0.12065 -0.2794)
			(end 0.12065 -0.3048)
			(stroke
				(width 0.1)
				(type default)
			)
			(layer "F.Fab")
		)
		(fp_line
			(start 0.67945 -0.3048)
			(end 0.67945 0.3048)
			(stroke
				(width 0.1)
				(type default)
			)
			(layer "F.Fab")
		)
		(fp_line
			(start 0.67945 0.3048)
			(end 0.120396 0.3048)
			(stroke
				(width 0.1)
				(type default)
			)
			(layer "F.Fab")
		)
		(pad "1" smd circle
			(at -0.40005 0)
			(size 0 0)
			(layers "F.Cu" "F.Mask" "F.Paste")
			(net "HP_NIC2_PWRGD_R")
		)
		(pad "2" smd circle
			(at 0.40005 0)
			(size 0 0)
			(layers "F.Cu" "F.Mask" "F.Paste")
			(net "HP_NIC2_PWRGD")
		)
	)
)
